(kicad_pcb
	(version 20260206)
	(generator "pcbnew")
	(generator_version "10.0")
	(general
		(thickness 1.6)
		(legacy_teardrops no)
	)
	(paper "A4")
	(title_block
		(title "netronome-mezz — pcbd0082-001_rev01_jul9_a.brd")
		(comment 1 "Open CloudServer (Microsoft) / footprints 13-15 of 714")
	)
	(layers
		(0 "F.Cu" signal "TOP")
		(4 "In1.Cu" signal "02_GND")
		(6 "In2.Cu" signal "03_SIG")
		(8 "In3.Cu" signal "04_SIG")
		(10 "In4.Cu" signal "05_GND")
		(12 "In5.Cu" signal "06_PWR1")
		(14 "In6.Cu" signal "07_SIG")
		(16 "In7.Cu" signal "08_SIG")
		(18 "In8.Cu" signal "09_GND")
		(2 "B.Cu" signal "BOTTOM")
		(9 "F.Adhes" user "F.Adhesive")
		(11 "B.Adhes" user "B.Adhesive")
		(13 "F.Paste" user "Package Geometry/Pastemask Top")
		(15 "B.Paste" user "Package Geometry/Pastemask Bottom")
		(5 "F.SilkS" user "Ref Des/Silkscreen Top")
		(7 "B.SilkS" user "Ref Des/Silkscreen Bottom")
		(1 "F.Mask" user "Board Geometry/Soldermask Top")
		(3 "B.Mask" user "Board Geometry/Soldermask Bottom")
		(17 "Dwgs.User" user "User.Drawings")
		(19 "Cmts.User" user "User.Comments")
		(21 "Eco1.User" user "User.Eco1")
		(23 "Eco2.User" user "User.Eco2")
		(25 "Edge.Cuts" user "Board Geometry/Outline")
		(27 "Margin" user)
		(31 "F.CrtYd" user "Package Geometry/Place Bound Top")
		(29 "B.CrtYd" user "Package Geometry/Place Bound Bottom")
		(35 "F.Fab" user "Ref Des/Assembly Top")
		(33 "B.Fab" user "Ref Des/Assembly Bottom")
		(45 "User.4" user "COMPVAL_TYPE_BOTTOM")
	)
	(footprint ""
		(layer "F.Cu")
		(at 81.6356 41.529)
		(property "Reference" "U3"
			(at -2.1336 -2.51333 0)
			(unlocked yes)
			(layer "F.SilkS")
			(effects
				(font
					(size 0.7874 0.5842)
					(thickness 0.127)
				)
				(justify left)
			)
		)
		(property "Value" "*"
			(at -0.4826 -0.105105 0)
			(unlocked yes)
			(layer "F.Fab")
			(hide yes)
			(effects
				(font
					(size 1.27 0.9652)
					(thickness 0.000001)
				)
				(justify left)
			)
		)
		(property "Device Type" "DCDC0049"
			(at -0.4826 -0.105105 0)
			(unlocked yes)
			(layer "F.Fab")
			(hide yes)
			(effects
				(font
					(size 1.27 0.9652)
					(thickness 0.000001)
				)
				(justify left)
			)
		)
		(duplicate_pad_numbers_are_jumpers no)
		(fp_line
			(start -1.905 -1.905)
			(end -1.27 -1.905)
			(stroke
				(width 0.1524)
				(type default)
			)
			(layer "F.SilkS")
		)
		(fp_line
			(start -1.905 -1.905)
			(end -1.27 -1.905)
			(stroke
				(width 0.1524)
				(type default)
			)
			(layer "F.SilkS")
		)
		(fp_line
			(start -1.905 -1.27)
			(end -1.905 -1.905)
			(stroke
				(width 0.1524)
				(type default)
			)
			(layer "F.SilkS")
		)
		(fp_line
			(start -1.905 -1.27)
			(end -1.905 -1.905)
			(stroke
				(width 0.1524)
				(type default)
			)
			(layer "F.SilkS")
		)
		(fp_line
			(start -1.905 -1.27)
			(end -1.27 -1.905)
			(stroke
				(width 0.1524)
				(type default)
			)
			(layer "F.SilkS")
		)
		(fp_line
			(start -1.905 -1.27)
			(end -1.27 -1.905)
			(stroke
				(width 0.1524)
				(type default)
			)
			(layer "F.SilkS")
		)
		(fp_line
			(start -1.905 1.905)
			(end -1.905 1.27)
			(stroke
				(width 0.1524)
				(type default)
			)
			(layer "F.SilkS")
		)
		(fp_line
			(start -1.27 1.905)
			(end -1.905 1.905)
			(stroke
				(width 0.1524)
				(type default)
			)
			(layer "F.SilkS")
		)
		(fp_line
			(start 1.27 -1.905)
			(end 1.905 -1.905)
			(stroke
				(width 0.1524)
				(type default)
			)
			(layer "F.SilkS")
		)
		(fp_line
			(start 1.27 1.905)
			(end 1.905 1.905)
			(stroke
				(width 0.1524)
				(type default)
			)
			(layer "F.SilkS")
		)
		(fp_line
			(start 1.27 1.905)
			(end 1.905 1.905)
			(stroke
				(width 0.1524)
				(type default)
			)
			(layer "F.SilkS")
		)
		(fp_line
			(start 1.905 -1.905)
			(end 1.905 -1.27)
			(stroke
				(width 0.1524)
				(type default)
			)
			(layer "F.SilkS")
		)
		(fp_line
			(start 1.905 -1.905)
			(end 1.905 -1.27)
			(stroke
				(width 0.1524)
				(type default)
			)
			(layer "F.SilkS")
		)
		(fp_line
			(start 1.905 1.905)
			(end 1.905 1.27)
			(stroke
				(width 0.1524)
				(type default)
			)
			(layer "F.SilkS")
		)
		(fp_arc
			(start -2.39776 -1.207389)
			(mid -2.345186 -1.236366)
			(end -2.286 -1.246403)
			(stroke
				(width 0.1524)
				(type default)
			)
			(layer "F.SilkS")
		)
		(fp_arc
			(start -2.286 -1.246403)
			(mid -2.249785 -1.242714)
			(end -2.215058 -1.231798)
			(stroke
				(width 0.1524)
				(type default)
			)
			(layer "F.SilkS")
		)
		(fp_circle
			(center -2.286 -1.0668)
			(end -2.106397 -1.0668)
			(stroke
				(width 0.1524)
				(type default)
			)
			(fill no)
			(layer "F.SilkS")
		)
		(fp_poly
			(pts
				(xy -2.54 2.54) (xy 2.54 2.54) (xy 2.54 -2.54) (xy -1.093597 -2.54) (xy -1.093597 -2.202104) (xy -2.353589 -0.942111)
				(xy -2.54 -0.942111)
			)
			(stroke
				(width 0)
				(type default)
			)
			(fill no)
			(layer "F.CrtYd")
		)
		(fp_line
			(start -1.5494 -1.5494)
			(end -1.5494 1.5494)
			(stroke
				(width 0.1524)
				(type default)
			)
			(layer "F.Fab")
		)
		(fp_line
			(start -1.5494 1.5494)
			(end 1.5494 1.5494)
			(stroke
				(width 0.1524)
				(type default)
			)
			(layer "F.Fab")
		)
		(fp_line
			(start -1.524 -1.016)
			(end -1.016 -1.524)
			(stroke
				(width 0.1524)
				(type default)
			)
			(layer "F.Fab")
		)
		(fp_line
			(start 1.5494 -1.5494)
			(end -1.5494 -1.5494)
			(stroke
				(width 0.1524)
				(type default)
			)
			(layer "F.Fab")
		)
		(fp_line
			(start 1.5494 1.5494)
			(end 1.5494 -1.5494)
			(stroke
				(width 0.1524)
				(type default)
			)
			(layer "F.Fab")
		)
		(fp_circle
			(center -0.889 -0.889)
			(end -0.605003 -0.889)
			(stroke
				(width 0.1524)
				(type default)
			)
			(fill no)
			(layer "F.Fab")
		)
		(pad "1" smd custom
			(at -1.4986 -0.799998 270)
			(size 0.0508 0.0508)
			(layers "F.Cu" "F.Mask" "F.Paste")
			(net "11N2199")
			(options
				(clearance outline)
				(anchor circle)
			)
			(primitives
				(gr_poly
					(pts
						(arc
							(start -0.1016 -0.3048)
							(mid 0 -0.4064)
							(end 0.1016 -0.3048)
						)
						(xy 0.1016 0.4064) (xy -0.1016 0.4064)
					)
					(width 0)
					(fill yes)
				)
			)
		)
		(pad "2" smd custom
			(at -1.4986 -0.399999 270)
			(size 0.0508 0.0508)
			(layers "F.Cu" "F.Mask" "F.Paste")
			(net "DDR_VDDQ")
			(options
				(clearance outline)
				(anchor circle)
			)
			(primitives
				(gr_poly
					(pts
						(arc
							(start -0.1016 -0.3048)
							(mid 0 -0.4064)
							(end 0.1016 -0.3048)
						)
						(xy 0.1016 0.4064) (xy -0.1016 0.4064)
					)
					(width 0)
					(fill yes)
				)
			)
		)
		(pad "3" smd custom
			(at -1.4986 0 270)
			(size 0.0508 0.0508)
			(layers "F.Cu" "F.Mask" "F.Paste")
			(net "DDR_VTT")
			(options
				(clearance outline)
				(anchor circle)
			)
			(primitives
				(gr_poly
					(pts
						(arc
							(start -0.1016 -0.3048)
							(mid 0 -0.4064)
							(end 0.1016 -0.3048)
						)
						(xy 0.1016 0.4064) (xy -0.1016 0.4064)
					)
					(width 0)
					(fill yes)
				)
			)
		)
		(pad "4" smd custom
			(at -1.4986 0.399999 270)
			(size 0.0508 0.0508)
			(layers "F.Cu" "F.Mask" "F.Paste")
			(net "GND")
			(options
				(clearance outline)
				(anchor circle)
			)
			(primitives
				(gr_poly
					(pts
						(arc
							(start -0.1016 -0.3048)
							(mid 0 -0.4064)
							(end 0.1016 -0.3048)
						)
						(xy 0.1016 0.4064) (xy -0.1016 0.4064)
					)
					(width 0)
					(fill yes)
				)
			)
		)
		(pad "5" smd custom
			(at -1.4986 0.799998 270)
			(size 0.0508 0.0508)
			(layers "F.Cu" "F.Mask" "F.Paste")
			(net "11N2202")
			(options
				(clearance outline)
				(anchor circle)
			)
			(primitives
				(gr_poly
					(pts
						(arc
							(start -0.1016 -0.3048)
							(mid 0 -0.4064)
							(end 0.1016 -0.3048)
						)
						(xy 0.1016 0.4064) (xy -0.1016 0.4064)
					)
					(width 0)
					(fill yes)
				)
			)
		)
		(pad "6" smd custom
			(at -0.799998 1.4986)
			(size 0.0508 0.0508)
			(layers "F.Cu" "F.Mask" "F.Paste")
			(net "11N2152")
			(options
				(clearance outline)
				(anchor circle)
			)
			(primitives
				(gr_poly
					(pts
						(arc
							(start -0.1016 -0.3048)
							(mid 0 -0.4064)
							(end 0.1016 -0.3048)
						)
						(xy 0.1016 0.4064) (xy -0.1016 0.4064)
					)
					(width 0)
					(fill yes)
				)
			)
		)
		(pad "7" smd custom
			(at -0.399999 1.4986)
			(size 0.0508 0.0508)
			(layers "F.Cu" "F.Mask" "F.Paste")
			(net "GND")
			(options
				(clearance outline)
				(anchor circle)
			)
			(primitives
				(gr_poly
					(pts
						(arc
							(start -0.1016 -0.3048)
							(mid 0 -0.4064)
							(end 0.1016 -0.3048)
						)
						(xy 0.1016 0.4064) (xy -0.1016 0.4064)
					)
					(width 0)
					(fill yes)
				)
			)
		)
		(pad "8" smd custom
			(at 0 1.4986)
			(size 0.0508 0.0508)
			(layers "F.Cu" "F.Mask" "F.Paste")
			(net "11N2146")
			(options
				(clearance outline)
				(anchor circle)
			)
			(primitives
				(gr_poly
					(pts
						(arc
							(start -0.1016 -0.3048)
							(mid 0 -0.4064)
							(end 0.1016 -0.3048)
						)
						(xy 0.1016 0.4064) (xy -0.1016 0.4064)
					)
					(width 0)
					(fill yes)
				)
			)
		)
		(pad "9" smd custom
			(at 0.399999 1.4986)
			(size 0.0508 0.0508)
			(layers "F.Cu" "F.Mask" "F.Paste")
			(net "11N2191")
			(options
				(clearance outline)
				(anchor circle)
			)
			(primitives
				(gr_poly
					(pts
						(arc
							(start -0.1016 -0.3048)
							(mid 0 -0.4064)
							(end 0.1016 -0.3048)
						)
						(xy 0.1016 0.4064) (xy -0.1016 0.4064)
					)
					(width 0)
					(fill yes)
				)
			)
		)
		(pad "10" smd custom
			(at 0.799998 1.4986)
			(size 0.0508 0.0508)
			(layers "F.Cu" "F.Mask" "F.Paste")
			(net "GND")
			(options
				(clearance outline)
				(anchor circle)
			)
			(primitives
				(gr_poly
					(pts
						(arc
							(start -0.1016 -0.3048)
							(mid 0 -0.4064)
							(end 0.1016 -0.3048)
						)
						(xy 0.1016 0.4064) (xy -0.1016 0.4064)
					)
					(width 0)
					(fill yes)
				)
			)
		)
		(pad "11" smd custom
			(at 1.4986 0.799998 90)
			(size 0.0508 0.0508)
			(layers "F.Cu" "F.Mask" "F.Paste")
			(net "11N2177")
			(options
				(clearance outline)
				(anchor circle)
			)
			(primitives
				(gr_poly
					(pts
						(arc
							(start -0.1016 -0.3048)
							(mid 0 -0.4064)
							(end 0.1016 -0.3048)
						)
						(xy 0.1016 0.4064) (xy -0.1016 0.4064)
					)
					(width 0)
					(fill yes)
				)
			)
		)
		(pad "12" smd custom
			(at 1.4986 0.399999 90)
			(size 0.0508 0.0508)
			(layers "F.Cu" "F.Mask" "F.Paste")
			(net "11N2159")
			(options
				(clearance outline)
				(anchor circle)
			)
			(primitives
				(gr_poly
					(pts
						(arc
							(start -0.1016 -0.3048)
							(mid 0 -0.4064)
							(end 0.1016 -0.3048)
						)
						(xy 0.1016 0.4064) (xy -0.1016 0.4064)
					)
					(width 0)
					(fill yes)
				)
			)
		)
		(pad "13" smd custom
			(at 1.4986 0 90)
			(size 0.0508 0.0508)
			(layers "F.Cu" "F.Mask" "F.Paste")
			(net "11N2175")
			(options
				(clearance outline)
				(anchor circle)
			)
			(primitives
				(gr_poly
					(pts
						(arc
							(start -0.1016 -0.3048)
							(mid 0 -0.4064)
							(end 0.1016 -0.3048)
						)
						(xy 0.1016 0.4064) (xy -0.1016 0.4064)
					)
					(width 0)
					(fill yes)
				)
			)
		)
		(pad "14" smd custom
			(at 1.4986 -0.399999 90)
			(size 0.0508 0.0508)
			(layers "F.Cu" "F.Mask" "F.Paste")
			(net "11N2173")
			(options
				(clearance outline)
				(anchor circle)
			)
			(primitives
				(gr_poly
					(pts
						(arc
							(start -0.1016 -0.3048)
							(mid 0 -0.4064)
							(end 0.1016 -0.3048)
						)
						(xy 0.1016 0.4064) (xy -0.1016 0.4064)
					)
					(width 0)
					(fill yes)
				)
			)
		)
		(pad "15" smd custom
			(at 1.4986 -0.799998 90)
			(size 0.0508 0.0508)
			(layers "F.Cu" "F.Mask" "F.Paste")
			(net "11N2179")
			(options
				(clearance outline)
				(anchor circle)
			)
			(primitives
				(gr_poly
					(pts
						(arc
							(start -0.1016 -0.3048)
							(mid 0 -0.4064)
							(end 0.1016 -0.3048)
						)
						(xy 0.1016 0.4064) (xy -0.1016 0.4064)
					)
					(width 0)
					(fill yes)
				)
			)
		)
		(pad "16" smd custom
			(at 0.799998 -1.4986 180)
			(size 0.0508 0.0508)
			(layers "F.Cu" "F.Mask" "F.Paste")
			(net "VDDQ_VTT_EN")
			(options
				(clearance outline)
				(anchor circle)
			)
			(primitives
				(gr_poly
					(pts
						(arc
							(start -0.1016 -0.3048)
							(mid 0 -0.4064)
							(end 0.1016 -0.3048)
						)
						(xy 0.1016 0.4064) (xy -0.1016 0.4064)
					)
					(width 0)
					(fill yes)
				)
			)
		)
		(pad "17" smd custom
			(at 0.399999 -1.4986 180)
			(size 0.0508 0.0508)
			(layers "F.Cu" "F.Mask" "F.Paste")
			(net "VDDQ_VTT_EN")
			(options
				(clearance outline)
				(anchor circle)
			)
			(primitives
				(gr_poly
					(pts
						(arc
							(start -0.1016 -0.3048)
							(mid 0 -0.4064)
							(end 0.1016 -0.3048)
						)
						(xy 0.1016 0.4064) (xy -0.1016 0.4064)
					)
					(width 0)
					(fill yes)
				)
			)
		)
		(pad "18" smd custom
			(at 0 -1.4986 180)
			(size 0.0508 0.0508)
			(layers "F.Cu" "F.Mask" "F.Paste")
			(net "11N2140")
			(options
				(clearance outline)
				(anchor circle)
			)
			(primitives
				(gr_poly
					(pts
						(arc
							(start -0.1016 -0.3048)
							(mid 0 -0.4064)
							(end 0.1016 -0.3048)
						)
						(xy 0.1016 0.4064) (xy -0.1016 0.4064)
					)
					(width 0)
					(fill yes)
				)
			)
		)
		(pad "19" smd custom
			(at -0.399999 -1.4986 180)
			(size 0.0508 0.0508)
			(layers "F.Cu" "F.Mask" "F.Paste")
			(net "11N2138")
			(options
				(clearance outline)
				(anchor circle)
			)
			(primitives
				(gr_poly
					(pts
						(arc
							(start -0.1016 -0.3048)
							(mid 0 -0.4064)
							(end 0.1016 -0.3048)
						)
						(xy 0.1016 0.4064) (xy -0.1016 0.4064)
					)
					(width 0)
					(fill yes)
				)
			)
		)
		(pad "20" smd custom
			(at -0.799998 -1.4986 180)
			(size 0.0508 0.0508)
			(layers "F.Cu" "F.Mask" "F.Paste")
			(net "VDDQ_VTT_PGOOD")
			(options
				(clearance outline)
				(anchor circle)
			)
			(primitives
				(gr_poly
					(pts
						(arc
							(start -0.1016 -0.3048)
							(mid 0 -0.4064)
							(end 0.1016 -0.3048)
						)
						(xy 0.1016 0.4064) (xy -0.1016 0.4064)
					)
					(width 0)
					(fill yes)
				)
			)
		)
		(pad "21" smd rect
			(at 0 0)
			(size 1.5748 1.5748)
			(layers "F.Cu" "F.Mask" "F.Paste")
			(net "GND")
		)
	)
	(footprint ""
		(layer "F.Cu")
		(at 53.594 36.957 90)
		(property "Reference" "R167"
			(at 0.22733 1.27 0)
			(unlocked yes)
			(layer "F.SilkS")
			(effects
				(font
					(size 0.7874 0.5842)
					(thickness 0.127)
				)
				(justify left)
			)
		)
		(property "Value" "0"
			(at -0.148158 1.3462 180)
			(unlocked yes)
			(layer "F.Fab")
			(hide yes)
			(effects
				(font
					(size 1.27 0.9652)
					(thickness 0.000001)
				)
				(justify left)
			)
		)
		(property "Device Type" "REST1111"
			(at -0.148158 1.3462 180)
			(unlocked yes)
			(layer "F.Fab")
			(hide yes)
			(effects
				(font
					(size 1.27 0.9652)
					(thickness 0.000001)
				)
				(justify left)
			)
		)
		(duplicate_pad_numbers_are_jumpers no)
		(fp_poly
			(pts
				(xy 0.635 1.0668) (xy 0.635 -1.0668) (xy -0.635 -1.0668) (xy -0.635 1.0668)
			)
			(stroke
				(width 0)
				(type default)
			)
			(fill no)
			(layer "F.CrtYd")
		)
		(fp_line
			(start 0.254 -0.508)
			(end 0.254 0.508)
			(stroke
				(width 0.0254)
				(type default)
			)
			(layer "F.Fab")
		)
		(fp_line
			(start -0.254 -0.508)
			(end 0.254 -0.508)
			(stroke
				(width 0.0254)
				(type default)
			)
			(layer "F.Fab")
		)
		(fp_line
			(start 0.254 0.508)
			(end -0.254 0.508)
			(stroke
				(width 0.0254)
				(type default)
			)
			(layer "F.Fab")
		)
		(fp_line
			(start -0.254 0.508)
			(end -0.254 -0.508)
			(stroke
				(width 0.0254)
				(type default)
			)
			(layer "F.Fab")
		)
		(pad "1" smd rect
			(at 0 -0.4191 90)
			(size 0.508 0.5334)
			(layers "F.Cu" "F.Mask" "F.Paste")
			(net "VDD_CORE")
		)
		(pad "2" smd rect
			(at 0 0.4191 90)
			(size 0.508 0.5334)
			(layers "F.Cu" "F.Mask" "F.Paste")
			(net "NFP_VDD_CORE_ISEN2_N")
		)
		(zone
			(layer "F.Cu")
			(hatch none 0.5)
			(connect_pads
				(clearance 0)
			)
			(min_thickness 0.25)
			(keepout
				(tracks not_allowed)
				(vias allowed)
				(pads allowed)
				(copperpour not_allowed)
				(footprints allowed)
			)
			(placement
				(enabled no)
				(sheetname "")
			)
			(fill
				(thermal_gap 0.5)
				(thermal_bridge_width 0.5)
				(island_removal_mode 0)
			)
			(polygon
				(pts
					(xy 53.5686 36.9316) (xy 53.6194 36.9316) (xy 53.6194 36.9824) (xy 53.5686 36.9824)
				)
			)
		)
	)
	(footprint ""
		(layer "F.Cu")
		(at 61.2902 46.355 90)
		(property "Reference" "R2"
			(at -1.778 1.29667 90)
			(unlocked yes)
			(layer "F.SilkS")
			(effects
				(font
					(size 0.7874 0.5842)
					(thickness 0.127)
				)
				(justify left)
			)
		)
		(property "Value" "100K"
			(at -0.148158 1.7526 180)
			(unlocked yes)
			(layer "F.Fab")
			(hide yes)
			(effects
				(font
					(size 1.27 0.9652)
					(thickness 0.000001)
				)
				(justify left)
			)
		)
		(property "Device Type" "REST0288"
			(at -0.148158 1.7526 180)
			(unlocked yes)
			(layer "F.Fab")
			(hide yes)
			(effects
				(font
					(size 1.27 0.9652)
					(thickness 0.000001)
				)
				(justify left)
			)
		)
		(duplicate_pad_numbers_are_jumpers no)
		(fp_circle
			(center 0 0)
			(end 0 0.127)
			(stroke
				(width 0.2032)
				(type default)
			)
			(fill no)
			(layer "F.SilkS")
		)
		(fp_poly
			(pts
				(xy 0.7874 -1.6637) (xy -0.7874 -1.6637) (xy -0.7874 1.6637) (xy 0.7874 1.6637)
			)
			(stroke
				(width 0)
				(type default)
			)
			(fill no)
			(layer "F.CrtYd")
		)
		(fp_line
			(start 0.4064 -0.8128)
			(end 0.4064 0.8128)
			(stroke
				(width 0.0254)
				(type default)
			)
			(layer "F.Fab")
		)
		(fp_line
			(start -0.4064 -0.8128)
			(end 0.4064 -0.8128)
			(stroke
				(width 0.0254)
				(type default)
			)
			(layer "F.Fab")
		)
		(fp_line
			(start 0.4064 0.8128)
			(end -0.4064 0.8128)
			(stroke
				(width 0.0254)
				(type default)
			)
			(layer "F.Fab")
		)
		(fp_line
			(start -0.4064 0.8128)
			(end -0.4064 -0.8128)
			(stroke
				(width 0.0254)
				(type default)
			)
			(layer "F.Fab")
		)
		(pad "1" smd rect
			(at 0 -0.8001 90)
			(size 0.762 0.9652)
			(layers "F.Cu" "F.Mask" "F.Paste")
			(net "NFP_VDD_CORE_TCOMPB")
		)
		(pad "2" smd rect
			(at 0 0.8001 90)
			(size 0.762 0.9652)
			(layers "F.Cu" "F.Mask" "F.Paste")
			(net "NFP_VDD_CORE_TCOMPA")
		)
		(zone
			(layer "F.Cu")
			(hatch none 0.5)
			(connect_pads
				(clearance 0)
			)
			(min_thickness 0.25)
			(keepout
				(tracks not_allowed)
				(vias allowed)
				(pads allowed)
				(copperpour not_allowed)
				(footprints allowed)
			)
			(placement
				(enabled no)
				(sheetname "")
			)
			(fill
				(thermal_gap 0.5)
				(thermal_bridge_width 0.5)
				(island_removal_mode 0)
			)
			(polygon
				(pts
					(xy 61.0362 46.4185) (xy 61.0362 46.2915) (xy 61.5442 46.2915) (xy 61.5442 46.4185)
				)
			)
		)
	)
)
